# T6G (Grand Teton) — schematic netlist excerpt (pin names and nets, part order shuffled) for the footprints in the layout excerpt that follows; sources: Cadence DE-HDL packaged netlist, KiCad conversion of 04192023_DAF0TMB3IC0_F0TG_MB_C_brd_V02_OCP.brd

PC2225  Q_CAP  220PF 50V 10% EMPTY  pkg 0402  page 264 : A = HSC_ON ; B = AGND_HSC
PR511  Q_RES  1.5 1% EMPTY  pkg 0402LF  page 216 : A = SW_PVDDCR_SOC_P1_SW3_RC ; B = GND

(kicad_pcb
	(version 20260206)
	(generator "pcbnew")
	(generator_version "10.0")
	(general
		(thickness 1.6)
		(legacy_teardrops no)
	)
	(paper "A4")
	(title_block
		(title "04192023_DAF0TMB3IC0_F0TG_MB_C_brd_V02_OCP.brd")
		(comment 1 "Grand Teton / footprints 3710-3711 of 8354")
	)
	(layers
		(0 "F.Cu" signal "TOP")
		(4 "In1.Cu" signal "GND")
		(6 "In2.Cu" signal "IN1")
		(8 "In3.Cu" signal "GND1")
		(10 "In4.Cu" signal "IN2")
		(12 "In5.Cu" signal "GND2")
		(14 "In6.Cu" signal "IN3")
		(16 "In7.Cu" signal "GND3")
		(18 "In8.Cu" signal "VCC")
		(20 "In9.Cu" signal "VCC1")
		(22 "In10.Cu" signal "GND4")
		(24 "In11.Cu" signal "IN4")
		(26 "In12.Cu" signal "GND5")
		(28 "In13.Cu" signal "IN5")
		(30 "In14.Cu" signal "GND6")
		(32 "In15.Cu" signal "IN6")
		(34 "In16.Cu" signal "GND7")
		(2 "B.Cu" signal "BOTTOM")
		(9 "F.Adhes" user "F.Adhesive")
		(11 "B.Adhes" user "B.Adhesive")
		(13 "F.Paste" user "Package Geometry/Pastemask Top")
		(15 "B.Paste" user "Package Geometry/Pastemask Bottom")
		(5 "F.SilkS" user "Ref Des/Silkscreen Top")
		(7 "B.SilkS" user "Ref Des/Silkscreen Bottom")
		(1 "F.Mask" user "Board Geometry/Soldermask Top")
		(3 "B.Mask" user "Board Geometry/Soldermask Bottom")
		(17 "Dwgs.User" user "User.Drawings")
		(19 "Cmts.User" user "User.Comments")
		(21 "Eco1.User" user "User.Eco1")
		(23 "Eco2.User" user "User.Eco2")
		(25 "Edge.Cuts" user "Board Geometry/Outline")
		(27 "Margin" user)
		(31 "F.CrtYd" user "Package Geometry/Place Bound Top")
		(29 "B.CrtYd" user "Package Geometry/Place Bound Bottom")
		(35 "F.Fab" user "Ref Des/Assembly Top")
		(33 "B.Fab" user "Ref Des/Assembly Bottom")
	)
	(footprint ""
		(layer "F.Cu")
		(at 236.7661 -401.887182)
		(property "Reference" "PC2225"
			(at 0 0 0)
			(layer "F.SilkS")
			(hide yes)
			(effects
				(font
					(size 1.27 1.27)
				)
			)
		)
		(property "Value" ""
			(at 0 0 0)
			(layer "F.Fab")
			(effects
				(font
					(size 1.27 1.27)
				)
			)
		)
		(duplicate_pad_numbers_are_jumpers no)
		(fp_line
			(start -0.7874 -0.4064)
			(end 0.7874 -0.4064)
			(stroke
				(width 0.1524)
				(type default)
			)
			(layer "F.SilkS")
		)
		(fp_line
			(start -0.7874 0.4064)
			(end -0.7874 -0.4064)
			(stroke
				(width 0.1524)
				(type default)
			)
			(layer "F.SilkS")
		)
		(fp_line
			(start 0.7874 -0.4064)
			(end 0.7874 0.4064)
			(stroke
				(width 0.1524)
				(type default)
			)
			(layer "F.SilkS")
		)
		(fp_line
			(start 0.7874 0.4064)
			(end -0.7874 0.4064)
			(stroke
				(width 0.1524)
				(type default)
			)
			(layer "F.SilkS")
		)
		(fp_line
			(start -0.67945 -0.305054)
			(end -0.12065 -0.305054)
			(stroke
				(width 0.1)
				(type default)
			)
			(layer "F.Fab")
		)
		(fp_line
			(start -0.67945 0.3048)
			(end -0.67945 -0.305054)
			(stroke
				(width 0.1)
				(type default)
			)
			(layer "F.Fab")
		)
		(fp_line
			(start -0.12065 -0.305054)
			(end -0.12065 -0.2794)
			(stroke
				(width 0.1)
				(type default)
			)
			(layer "F.Fab")
		)
		(fp_line
			(start -0.12065 -0.2794)
			(end 0.12065 -0.2794)
			(stroke
				(width 0.1)
				(type default)
			)
			(layer "F.Fab")
		)
		(fp_line
			(start -0.12065 0.2794)
			(end -0.12065 0.3048)
			(stroke
				(width 0.1)
				(type default)
			)
			(layer "F.Fab")
		)
		(fp_line
			(start -0.12065 0.3048)
			(end -0.67945 0.3048)
			(stroke
				(width 0.1)
				(type default)
			)
			(layer "F.Fab")
		)
		(fp_line
			(start 0.120396 0.2794)
			(end -0.12065 0.2794)
			(stroke
				(width 0.1)
				(type default)
			)
			(layer "F.Fab")
		)
		(fp_line
			(start 0.120396 0.3048)
			(end 0.120396 0.2794)
			(stroke
				(width 0.1)
				(type default)
			)
			(layer "F.Fab")
		)
		(fp_line
			(start 0.12065 -0.3048)
			(end 0.67945 -0.3048)
			(stroke
				(width 0.1)
				(type default)
			)
			(layer "F.Fab")
		)
		(fp_line
			(start 0.12065 -0.2794)
			(end 0.12065 -0.3048)
			(stroke
				(width 0.1)
				(type default)
			)
			(layer "F.Fab")
		)
		(fp_line
			(start 0.67945 -0.3048)
			(end 0.67945 0.3048)
			(stroke
				(width 0.1)
				(type default)
			)
			(layer "F.Fab")
		)
		(fp_line
			(start 0.67945 0.3048)
			(end 0.120396 0.3048)
			(stroke
				(width 0.1)
				(type default)
			)
			(layer "F.Fab")
		)
		(pad "1" smd circle
			(at -0.40005 0)
			(size 0 0)
			(layers "F.Cu" "F.Mask" "F.Paste")
			(net "HSC_ON")
		)
		(pad "2" smd circle
			(at 0.40005 0)
			(size 0 0)
			(layers "F.Cu" "F.Mask" "F.Paste")
			(net "AGND_HSC")
		)
	)
	(footprint ""
		(layer "F.Cu")
		(at 136.101328 -158.265368 -90)
		(property "Reference" "PR511"
			(at 0 0 270)
			(layer "F.SilkS")
			(hide yes)
			(effects
				(font
					(size 1.27 1.27)
				)
			)
		)
		(property "Value" ""
			(at 0 0 270)
			(layer "F.Fab")
			(effects
				(font
					(size 1.27 1.27)
				)
			)
		)
		(duplicate_pad_numbers_are_jumpers no)
		(fp_line
			(start -0.7874 0.4064)
			(end -0.7874 -0.4064)
			(stroke
				(width 0.1524)
				(type default)
			)
			(layer "F.SilkS")
		)
		(fp_line
			(start 0.7874 0.4064)
			(end -0.7874 0.4064)
			(stroke
				(width 0.1524)
				(type default)
			)
			(layer "F.SilkS")
		)
		(fp_line
			(start -0.7874 -0.4064)
			(end 0.7874 -0.4064)
			(stroke
				(width 0.1524)
				(type default)
			)
			(layer "F.SilkS")
		)
		(fp_line
			(start 0.7874 -0.4064)
			(end 0.7874 0.4064)
			(stroke
				(width 0.1524)
				(type default)
			)
			(layer "F.SilkS")
		)
		(fp_line
			(start -0.67945 0.3048)
			(end -0.67945 -0.305054)
			(stroke
				(width 0.1)
				(type default)
			)
			(layer "F.Fab")
		)
		(fp_line
			(start -0.12065 0.3048)
			(end -0.67945 0.3048)
			(stroke
				(width 0.1)
				(type default)
			)
			(layer "F.Fab")
		)
		(fp_line
			(start 0.120396 0.3048)
			(end 0.120396 0.2794)
			(stroke
				(width 0.1)
				(type default)
			)
			(layer "F.Fab")
		)
		(fp_line
			(start 0.67945 0.3048)
			(end 0.120396 0.3048)
			(stroke
				(width 0.1)
				(type default)
			)
			(layer "F.Fab")
		)
		(fp_line
			(start -0.12065 0.2794)
			(end -0.12065 0.3048)
			(stroke
				(width 0.1)
				(type default)
			)
			(layer "F.Fab")
		)
		(fp_line
			(start 0.120396 0.2794)
			(end -0.12065 0.2794)
			(stroke
				(width 0.1)
				(type default)
			)
			(layer "F.Fab")
		)
		(fp_line
			(start -0.12065 -0.2794)
			(end 0.12065 -0.2794)
			(stroke
				(width 0.1)
				(type default)
			)
			(layer "F.Fab")
		)
		(fp_line
			(start 0.12065 -0.2794)
			(end 0.12065 -0.3048)
			(stroke
				(width 0.1)
				(type default)
			)
			(layer "F.Fab")
		)
		(fp_line
			(start 0.12065 -0.3048)
			(end 0.67945 -0.3048)
			(stroke
				(width 0.1)
				(type default)
			)
			(layer "F.Fab")
		)
		(fp_line
			(start 0.67945 -0.3048)
			(end 0.67945 0.3048)
			(stroke
				(width 0.1)
				(type default)
			)
			(layer "F.Fab")
		)
		(fp_line
			(start -0.67945 -0.305054)
			(end -0.12065 -0.305054)
			(stroke
				(width 0.1)
				(type default)
			)
			(layer "F.Fab")
		)
		(fp_line
			(start -0.12065 -0.305054)
			(end -0.12065 -0.2794)
			(stroke
				(width 0.1)
				(type default)
			)
			(layer "F.Fab")
		)
		(pad "1" smd circle
			(at -0.40005 0 270)
			(size 0 0)
			(layers "F.Cu" "F.Mask" "F.Paste")
			(net "SW_PVDDCR_SOC_P1_SW3_RC")
		)
		(pad "2" smd circle
			(at 0.40005 0 270)
			(size 0 0)
			(layers "F.Cu" "F.Mask" "F.Paste")
			(net "GND")
		)
	)
)
